# BASEBOARD_FAB2 (Tioga Pass) — schematic netlist excerpt (pin names and nets, part order shuffled) for the footprints in the layout excerpt that follows; sources: Cadence DE-HDL packaged netlist, KiCad conversion of Wiwynn_Tioga_Pass_MB.brd

C1L10  CAP_A  1.0UF 6.3V 10% X6S  pkg 0402V  page 175 : A = FP_RST_BTN_R_N ; B = GND
C6B10  CAP  0.22UF 16V 10% X7R  pkg 0402  page 105 : A = P3E_CPU0_PE1_PCH_TXP<13> ; B = P3E_CPU0_PE1_PCH_C_TXP<13>
CT49  CAP  1000PF 50V 10% X7R  pkg 0402LF  page 216 : A = A_TSENSE_PVDDQ_ABC ; B = GND

(kicad_pcb
	(version 20260206)
	(generator "pcbnew")
	(generator_version "10.0")
	(general
		(thickness 1.6)
		(legacy_teardrops no)
	)
	(paper "A4")
	(title_block
		(title "Wiwynn_Tioga_Pass_MB.brd")
		(comment 1 "Tioga Pass / footprints 981-983 of 4770")
	)
	(layers
		(0 "F.Cu" signal "TOP")
		(4 "In1.Cu" signal "L2GND")
		(6 "In2.Cu" signal "L3")
		(8 "In3.Cu" signal "L4GND")
		(10 "In4.Cu" signal "L5")
		(12 "In5.Cu" signal "L6GND")
		(14 "In6.Cu" signal "L7VCC")
		(16 "In7.Cu" signal "L8VCC")
		(18 "In8.Cu" signal "L9GND")
		(20 "In9.Cu" signal "L10")
		(22 "In10.Cu" signal "L11GND")
		(24 "In11.Cu" signal "L12")
		(26 "In12.Cu" signal "L13GND")
		(2 "B.Cu" signal "BOTTOM")
		(9 "F.Adhes" user "F.Adhesive")
		(11 "B.Adhes" user "B.Adhesive")
		(13 "F.Paste" user "Package Geometry/Pastemask Top")
		(15 "B.Paste" user "Package Geometry/Pastemask Bottom")
		(5 "F.SilkS" user "Ref Des/Silkscreen Top")
		(7 "B.SilkS" user "Ref Des/Silkscreen Bottom")
		(1 "F.Mask" user "Board Geometry/Soldermask Top")
		(3 "B.Mask" user "Board Geometry/Soldermask Bottom")
		(17 "Dwgs.User" user "User.Drawings")
		(19 "Cmts.User" user "User.Comments")
		(21 "Eco1.User" user "User.Eco1")
		(23 "Eco2.User" user "User.Eco2")
		(25 "Edge.Cuts" user "Board Geometry/Outline")
		(27 "Margin" user)
		(31 "F.CrtYd" user "Package Geometry/Place Bound Top")
		(29 "B.CrtYd" user "Package Geometry/Place Bound Bottom")
		(35 "F.Fab" user "Ref Des/Assembly Top")
		(33 "B.Fab" user "Ref Des/Assembly Bottom")
	)
	(footprint ""
		(layer "F.Cu")
		(at 324.5485 -120.396 90)
		(property "Reference" "C6B10"
			(at -0.8382 -0.67818 90)
			(unlocked yes)
			(layer "F.SilkS")
			(effects
				(font
					(size 0.4064 0.254)
					(thickness 0.1524)
				)
				(justify left)
			)
		)
		(property "Value" ""
			(at 0 0 90)
			(layer "F.Fab")
			(effects
				(font
					(size 1.27 1.27)
				)
			)
		)
		(duplicate_pad_numbers_are_jumpers no)
		(fp_poly
			(pts
				(xy 0.3048 -0.1016) (xy 0.3048 0.9906) (xy -0.3048 0.9906) (xy -0.3048 -0.1016)
			)
			(stroke
				(width 0)
				(type default)
			)
			(fill no)
			(layer "F.CrtYd")
		)
		(fp_line
			(start 0.3048 -0.1016)
			(end -0.3048 -0.1016)
			(stroke
				(width 0.1)
				(type default)
			)
			(layer "F.Fab")
		)
		(fp_line
			(start -0.3048 -0.1016)
			(end -0.3048 0.9906)
			(stroke
				(width 0.1)
				(type default)
			)
			(layer "F.Fab")
		)
		(fp_line
			(start 0.3048 0.9906)
			(end 0.3048 -0.1016)
			(stroke
				(width 0.1)
				(type default)
			)
			(layer "F.Fab")
		)
		(fp_line
			(start -0.3048 0.9906)
			(end 0.3048 0.9906)
			(stroke
				(width 0.1)
				(type default)
			)
			(layer "F.Fab")
		)
		(pad "1" smd rect
			(at 0 0 90)
			(size 0.508 0.508)
			(layers "F.Cu" "F.Mask" "F.Paste")
			(net "P3E_CPU0_PE1_PCH_TXP<13>")
		)
		(pad "2" smd rect
			(at 0 0.889 90)
			(size 0.508 0.508)
			(layers "F.Cu" "F.Mask" "F.Paste")
			(net "P3E_CPU0_PE1_PCH_C_TXP<13>")
		)
		(zone
			(layer "F.Cu")
			(hatch none 0.5)
			(connect_pads
				(clearance 0)
			)
			(min_thickness 0.25)
			(keepout
				(tracks allowed)
				(vias not_allowed)
				(pads allowed)
				(copperpour not_allowed)
				(footprints allowed)
			)
			(placement
				(enabled no)
				(sheetname "")
			)
			(fill
				(thermal_gap 0.5)
				(thermal_bridge_width 0.5)
				(island_removal_mode 0)
			)
			(polygon
				(pts
					(xy 324.8025 -120.142) (xy 324.8025 -120.65) (xy 325.1835 -120.65) (xy 325.1835 -120.142)
				)
			)
		)
	)
	(footprint ""
		(layer "F.Cu")
		(at 479.6155 -142.875 90)
		(property "Reference" "C1L10"
			(at 0 0 90)
			(layer "F.SilkS")
			(hide yes)
			(effects
				(font
					(size 1.27 1.27)
				)
			)
		)
		(property "Value" ""
			(at 0 0 90)
			(layer "F.Fab")
			(effects
				(font
					(size 1.27 1.27)
				)
			)
		)
		(duplicate_pad_numbers_are_jumpers no)
		(fp_poly
			(pts
				(xy 0.3048 -0.1016) (xy 0.3048 0.9906) (xy -0.3048 0.9906) (xy -0.3048 -0.1016)
			)
			(stroke
				(width 0)
				(type default)
			)
			(fill no)
			(layer "F.CrtYd")
		)
		(fp_line
			(start 0.3048 -0.1016)
			(end -0.3048 -0.1016)
			(stroke
				(width 0.1)
				(type default)
			)
			(layer "F.Fab")
		)
		(fp_line
			(start -0.3048 -0.1016)
			(end -0.3048 0.9906)
			(stroke
				(width 0.1)
				(type default)
			)
			(layer "F.Fab")
		)
		(fp_line
			(start 0.3048 0.9906)
			(end 0.3048 -0.1016)
			(stroke
				(width 0.1)
				(type default)
			)
			(layer "F.Fab")
		)
		(fp_line
			(start -0.3048 0.9906)
			(end 0.3048 0.9906)
			(stroke
				(width 0.1)
				(type default)
			)
			(layer "F.Fab")
		)
		(pad "1" smd rect
			(at 0 0 90)
			(size 0.508 0.508)
			(layers "F.Cu" "F.Mask" "F.Paste")
			(net "FP_RST_BTN_R_N")
		)
		(pad "2" smd rect
			(at 0 0.889 90)
			(size 0.508 0.508)
			(layers "F.Cu" "F.Mask" "F.Paste")
			(net "GND")
		)
		(zone
			(layer "F.Cu")
			(hatch none 0.5)
			(connect_pads
				(clearance 0)
			)
			(min_thickness 0.25)
			(keepout
				(tracks allowed)
				(vias not_allowed)
				(pads allowed)
				(copperpour not_allowed)
				(footprints allowed)
			)
			(placement
				(enabled no)
				(sheetname "")
			)
			(fill
				(thermal_gap 0.5)
				(thermal_bridge_width 0.5)
				(island_removal_mode 0)
			)
			(polygon
				(pts
					(xy 479.8695 -142.621) (xy 479.8695 -143.129) (xy 480.2505 -143.129) (xy 480.2505 -142.621)
				)
			)
		)
		(zone
			(layer "F.Cu")
			(hatch none 0.5)
			(connect_pads
				(clearance 0)
			)
			(min_thickness 0.25)
			(keepout
				(tracks not_allowed)
				(vias allowed)
				(pads allowed)
				(copperpour not_allowed)
				(footprints allowed)
			)
			(placement
				(enabled no)
				(sheetname "")
			)
			(fill
				(thermal_gap 0.5)
				(thermal_bridge_width 0.5)
				(island_removal_mode 0)
			)
			(polygon
				(pts
					(xy 480.2505 -142.621) (xy 480.2505 -143.129) (xy 479.8695 -143.129) (xy 479.8695 -142.621)
				)
			)
		)
	)
	(footprint ""
		(layer "F.Cu")
		(at 351.5868 -8.0518 180)
		(property "Reference" "CT49"
			(at -1.1684 2.18567 180)
			(unlocked yes)
			(layer "F.SilkS")
			(effects
				(font
					(size 0.7874 0.5842)
					(thickness 0.1524)
				)
				(justify left)
			)
		)
		(property "Value" ""
			(at 0 0 180)
			(layer "F.Fab")
			(effects
				(font
					(size 1.27 1.27)
				)
			)
		)
		(duplicate_pad_numbers_are_jumpers no)
		(fp_poly
			(pts
				(xy 0.3048 -0.1016) (xy 0.3048 0.9906) (xy -0.3048 0.9906) (xy -0.3048 -0.1016)
			)
			(stroke
				(width 0)
				(type default)
			)
			(fill no)
			(layer "F.CrtYd")
		)
		(fp_line
			(start 0.3048 0.9906)
			(end 0.3048 -0.1016)
			(stroke
				(width 0.1)
				(type default)
			)
			(layer "F.Fab")
		)
		(fp_line
			(start 0.3048 -0.1016)
			(end -0.3048 -0.1016)
			(stroke
				(width 0.1)
				(type default)
			)
			(layer "F.Fab")
		)
		(fp_line
			(start -0.3048 0.9906)
			(end 0.3048 0.9906)
			(stroke
				(width 0.1)
				(type default)
			)
			(layer "F.Fab")
		)
		(fp_line
			(start -0.3048 -0.1016)
			(end -0.3048 0.9906)
			(stroke
				(width 0.1)
				(type default)
			)
			(layer "F.Fab")
		)
		(pad "1" smd rect
			(at 0 0 180)
			(size 0.508 0.508)
			(layers "F.Cu" "F.Mask" "F.Paste")
			(net "A_TSENSE_PVDDQ_ABC")
		)
		(pad "2" smd rect
			(at 0 0.889 180)
			(size 0.508 0.508)
			(layers "F.Cu" "F.Mask" "F.Paste")
			(net "GND")
		)
		(zone
			(layer "F.Cu")
			(hatch none 0.5)
			(connect_pads
				(clearance 0)
			)
			(min_thickness 0.25)
			(keepout
				(tracks not_allowed)
				(vias allowed)
				(pads allowed)
				(copperpour not_allowed)
				(footprints allowed)
			)
			(placement
				(enabled no)
				(sheetname "")
			)
			(fill
				(thermal_gap 0.5)
				(thermal_bridge_width 0.5)
				(island_removal_mode 0)
			)
			(polygon
				(pts
					(xy 351.8408 -8.6868) (xy 351.3328 -8.6868) (xy 351.3328 -8.3058) (xy 351.8408 -8.3058)
				)
			)
		)
		(zone
			(layer "F.Cu")
			(hatch none 0.5)
			(connect_pads
				(clearance 0)
			)
			(min_thickness 0.25)
			(keepout
				(tracks allowed)
				(vias not_allowed)
				(pads allowed)
				(copperpour not_allowed)
				(footprints allowed)
			)
			(placement
				(enabled no)
				(sheetname "")
			)
			(fill
				(thermal_gap 0.5)
				(thermal_bridge_width 0.5)
				(island_removal_mode 0)
			)
			(polygon
				(pts
					(xy 351.8408 -8.3058) (xy 351.3328 -8.3058) (xy 351.3328 -8.6868) (xy 351.8408 -8.6868)
				)
			)
		)
	)
)
